(kicad_pcb
	(version 20260206)
	(generator "pcbnew")
	(generator_version "10.0")
	(general
		(thickness 1.6)
		(legacy_teardrops no)
	)
	(paper "A4")
	(title_block
		(title "9052_F0T_PDB_Converter_Brick_F_V03_1208_1600_OCP.brd")
		(comment 1 "Grand Teton / footprints 325-330 of 578")
	)
	(layers
		(0 "F.Cu" signal "TOP")
		(4 "In1.Cu" signal "GND")
		(6 "In2.Cu" signal "IN1")
		(8 "In3.Cu" signal "GND1")
		(10 "In4.Cu" signal "VCC")
		(12 "In5.Cu" signal "VCC1")
		(14 "In6.Cu" signal "GND2")
		(16 "In7.Cu" signal "IN2")
		(18 "In8.Cu" signal "GND3")
		(2 "B.Cu" signal "BOTTOM")
		(9 "F.Adhes" user "F.Adhesive")
		(11 "B.Adhes" user "B.Adhesive")
		(13 "F.Paste" user "Package Geometry/Pastemask Top")
		(15 "B.Paste" user "Package Geometry/Pastemask Bottom")
		(5 "F.SilkS" user "Ref Des/Silkscreen Top")
		(7 "B.SilkS" user "Ref Des/Silkscreen Bottom")
		(1 "F.Mask" user "Board Geometry/Soldermask Top")
		(3 "B.Mask" user "Board Geometry/Soldermask Bottom")
		(17 "Dwgs.User" user "User.Drawings")
		(19 "Cmts.User" user "User.Comments")
		(21 "Eco1.User" user "User.Eco1")
		(23 "Eco2.User" user "User.Eco2")
		(25 "Edge.Cuts" user "Board Geometry/Outline")
		(27 "Margin" user)
		(31 "F.CrtYd" user "Package Geometry/Place Bound Top")
		(29 "B.CrtYd" user "Package Geometry/Place Bound Bottom")
		(35 "F.Fab" user "Ref Des/Assembly Top")
		(33 "B.Fab" user "Ref Des/Assembly Bottom")
	)
	(footprint ""
		(layer "B.Cu")
		(at 92.849954 -76.708 -90)
		(property "Reference" "PR67"
			(at 0 0 90)
			(layer "B.SilkS")
			(hide yes)
			(effects
				(font
					(size 1.27 1.27)
				)
				(justify mirror)
			)
		)
		(property "Value" ""
			(at 0 0 90)
			(layer "B.Fab")
			(effects
				(font
					(size 1.27 1.27)
				)
				(justify mirror)
			)
		)
		(duplicate_pad_numbers_are_jumpers no)
		(fp_line
			(start -0.7874 0.4064)
			(end 0.7874 0.4064)
			(stroke
				(width 0.1524)
				(type default)
			)
			(layer "B.SilkS")
		)
		(fp_line
			(start 0.7874 0.4064)
			(end 0.7874 -0.4064)
			(stroke
				(width 0.1524)
				(type default)
			)
			(layer "B.SilkS")
		)
		(fp_line
			(start -0.7874 -0.4064)
			(end -0.7874 0.4064)
			(stroke
				(width 0.1524)
				(type default)
			)
			(layer "B.SilkS")
		)
		(fp_line
			(start 0.7874 -0.4064)
			(end -0.7874 -0.4064)
			(stroke
				(width 0.1524)
				(type default)
			)
			(layer "B.SilkS")
		)
		(fp_line
			(start -0.67945 0.3048)
			(end -0.120396 0.3048)
			(stroke
				(width 0.1)
				(type default)
			)
			(layer "B.Fab")
		)
		(fp_line
			(start -0.120396 0.3048)
			(end -0.120396 0.2794)
			(stroke
				(width 0.1)
				(type default)
			)
			(layer "B.Fab")
		)
		(fp_line
			(start 0.12065 0.3048)
			(end 0.67945 0.3048)
			(stroke
				(width 0.1)
				(type default)
			)
			(layer "B.Fab")
		)
		(fp_line
			(start 0.67945 0.3048)
			(end 0.67945 -0.305054)
			(stroke
				(width 0.1)
				(type default)
			)
			(layer "B.Fab")
		)
		(fp_line
			(start -0.120396 0.2794)
			(end 0.12065 0.2794)
			(stroke
				(width 0.1)
				(type default)
			)
			(layer "B.Fab")
		)
		(fp_line
			(start 0.12065 0.2794)
			(end 0.12065 0.3048)
			(stroke
				(width 0.1)
				(type default)
			)
			(layer "B.Fab")
		)
		(fp_line
			(start -0.12065 -0.2794)
			(end -0.12065 -0.3048)
			(stroke
				(width 0.1)
				(type default)
			)
			(layer "B.Fab")
		)
		(fp_line
			(start 0.12065 -0.2794)
			(end -0.12065 -0.2794)
			(stroke
				(width 0.1)
				(type default)
			)
			(layer "B.Fab")
		)
		(fp_line
			(start -0.67945 -0.3048)
			(end -0.67945 0.3048)
			(stroke
				(width 0.1)
				(type default)
			)
			(layer "B.Fab")
		)
		(fp_line
			(start -0.12065 -0.3048)
			(end -0.67945 -0.3048)
			(stroke
				(width 0.1)
				(type default)
			)
			(layer "B.Fab")
		)
		(fp_line
			(start 0.12065 -0.305054)
			(end 0.12065 -0.2794)
			(stroke
				(width 0.1)
				(type default)
			)
			(layer "B.Fab")
		)
		(fp_line
			(start 0.67945 -0.305054)
			(end 0.12065 -0.305054)
			(stroke
				(width 0.1)
				(type default)
			)
			(layer "B.Fab")
		)
		(pad "1" smd circle
			(at 0.40005 0 90)
			(size 0 0)
			(layers "B.Cu" "B.Mask" "B.Paste")
			(net "P12V_MB1_SENSE-")
		)
		(pad "2" smd circle
			(at -0.40005 0 90)
			(size 0 0)
			(layers "B.Cu" "B.Mask" "B.Paste")
			(net "GND")
		)
	)
	(footprint ""
		(layer "B.Cu")
		(at 189.611 -88.3158)
		(property "Reference" "R132"
			(at 0 0 0)
			(layer "B.SilkS")
			(hide yes)
			(effects
				(font
					(size 1.27 1.27)
				)
				(justify mirror)
			)
		)
		(property "Value" ""
			(at 0 0 0)
			(layer "B.Fab")
			(effects
				(font
					(size 1.27 1.27)
				)
				(justify mirror)
			)
		)
		(duplicate_pad_numbers_are_jumpers no)
		(fp_line
			(start -0.7874 -0.4064)
			(end -0.7874 0.4064)
			(stroke
				(width 0.1524)
				(type default)
			)
			(layer "B.SilkS")
		)
		(fp_line
			(start -0.7874 0.4064)
			(end 0.7874 0.4064)
			(stroke
				(width 0.1524)
				(type default)
			)
			(layer "B.SilkS")
		)
		(fp_line
			(start 0.7874 -0.4064)
			(end -0.7874 -0.4064)
			(stroke
				(width 0.1524)
				(type default)
			)
			(layer "B.SilkS")
		)
		(fp_line
			(start 0.7874 0.4064)
			(end 0.7874 -0.4064)
			(stroke
				(width 0.1524)
				(type default)
			)
			(layer "B.SilkS")
		)
		(fp_line
			(start -0.67945 -0.3048)
			(end -0.67945 0.3048)
			(stroke
				(width 0.1)
				(type default)
			)
			(layer "B.Fab")
		)
		(fp_line
			(start -0.67945 0.3048)
			(end -0.120396 0.3048)
			(stroke
				(width 0.1)
				(type default)
			)
			(layer "B.Fab")
		)
		(fp_line
			(start -0.12065 -0.3048)
			(end -0.67945 -0.3048)
			(stroke
				(width 0.1)
				(type default)
			)
			(layer "B.Fab")
		)
		(fp_line
			(start -0.12065 -0.2794)
			(end -0.12065 -0.3048)
			(stroke
				(width 0.1)
				(type default)
			)
			(layer "B.Fab")
		)
		(fp_line
			(start -0.120396 0.2794)
			(end 0.12065 0.2794)
			(stroke
				(width 0.1)
				(type default)
			)
			(layer "B.Fab")
		)
		(fp_line
			(start -0.120396 0.3048)
			(end -0.120396 0.2794)
			(stroke
				(width 0.1)
				(type default)
			)
			(layer "B.Fab")
		)
		(fp_line
			(start 0.12065 -0.305054)
			(end 0.12065 -0.2794)
			(stroke
				(width 0.1)
				(type default)
			)
			(layer "B.Fab")
		)
		(fp_line
			(start 0.12065 -0.2794)
			(end -0.12065 -0.2794)
			(stroke
				(width 0.1)
				(type default)
			)
			(layer "B.Fab")
		)
		(fp_line
			(start 0.12065 0.2794)
			(end 0.12065 0.3048)
			(stroke
				(width 0.1)
				(type default)
			)
			(layer "B.Fab")
		)
		(fp_line
			(start 0.12065 0.3048)
			(end 0.67945 0.3048)
			(stroke
				(width 0.1)
				(type default)
			)
			(layer "B.Fab")
		)
		(fp_line
			(start 0.67945 -0.305054)
			(end 0.12065 -0.305054)
			(stroke
				(width 0.1)
				(type default)
			)
			(layer "B.Fab")
		)
		(fp_line
			(start 0.67945 0.3048)
			(end 0.67945 -0.305054)
			(stroke
				(width 0.1)
				(type default)
			)
			(layer "B.Fab")
		)
		(pad "1" smd circle
			(at 0.40005 0 180)
			(size 0 0)
			(layers "B.Cu" "B.Mask" "B.Paste")
			(net "SMB_P52V_HPDB_SDA")
		)
		(pad "2" smd circle
			(at -0.40005 0 180)
			(size 0 0)
			(layers "B.Cu" "B.Mask" "B.Paste")
			(net "P3V3_AUX")
		)
	)
	(footprint ""
		(layer "B.Cu")
		(at 136.85012 -114.046 90)
		(property "Reference" "C51"
			(at 0 0 90)
			(layer "B.SilkS")
			(hide yes)
			(effects
				(font
					(size 1.27 1.27)
				)
				(justify mirror)
			)
		)
		(property "Value" ""
			(at 0 0 90)
			(layer "B.Fab")
			(effects
				(font
					(size 1.27 1.27)
				)
				(justify mirror)
			)
		)
		(duplicate_pad_numbers_are_jumpers no)
		(fp_line
			(start 0.7874 -0.4064)
			(end -0.7874 -0.4064)
			(stroke
				(width 0.1524)
				(type default)
			)
			(layer "B.SilkS")
		)
		(fp_line
			(start -0.7874 -0.4064)
			(end -0.7874 0.4064)
			(stroke
				(width 0.1524)
				(type default)
			)
			(layer "B.SilkS")
		)
		(fp_line
			(start 0.7874 0.4064)
			(end 0.7874 -0.4064)
			(stroke
				(width 0.1524)
				(type default)
			)
			(layer "B.SilkS")
		)
		(fp_line
			(start -0.7874 0.4064)
			(end 0.7874 0.4064)
			(stroke
				(width 0.1524)
				(type default)
			)
			(layer "B.SilkS")
		)
		(fp_line
			(start 0.67945 -0.305054)
			(end 0.12065 -0.305054)
			(stroke
				(width 0.1)
				(type default)
			)
			(layer "B.Fab")
		)
		(fp_line
			(start 0.12065 -0.305054)
			(end 0.12065 -0.2794)
			(stroke
				(width 0.1)
				(type default)
			)
			(layer "B.Fab")
		)
		(fp_line
			(start -0.12065 -0.3048)
			(end -0.67945 -0.3048)
			(stroke
				(width 0.1)
				(type default)
			)
			(layer "B.Fab")
		)
		(fp_line
			(start -0.67945 -0.3048)
			(end -0.67945 0.3048)
			(stroke
				(width 0.1)
				(type default)
			)
			(layer "B.Fab")
		)
		(fp_line
			(start 0.12065 -0.2794)
			(end -0.12065 -0.2794)
			(stroke
				(width 0.1)
				(type default)
			)
			(layer "B.Fab")
		)
		(fp_line
			(start -0.12065 -0.2794)
			(end -0.12065 -0.3048)
			(stroke
				(width 0.1)
				(type default)
			)
			(layer "B.Fab")
		)
		(fp_line
			(start 0.12065 0.2794)
			(end 0.12065 0.3048)
			(stroke
				(width 0.1)
				(type default)
			)
			(layer "B.Fab")
		)
		(fp_line
			(start -0.120396 0.2794)
			(end 0.12065 0.2794)
			(stroke
				(width 0.1)
				(type default)
			)
			(layer "B.Fab")
		)
		(fp_line
			(start 0.67945 0.3048)
			(end 0.67945 -0.305054)
			(stroke
				(width 0.1)
				(type default)
			)
			(layer "B.Fab")
		)
		(fp_line
			(start 0.12065 0.3048)
			(end 0.67945 0.3048)
			(stroke
				(width 0.1)
				(type default)
			)
			(layer "B.Fab")
		)
		(fp_line
			(start -0.120396 0.3048)
			(end -0.120396 0.2794)
			(stroke
				(width 0.1)
				(type default)
			)
			(layer "B.Fab")
		)
		(fp_line
			(start -0.67945 0.3048)
			(end -0.120396 0.3048)
			(stroke
				(width 0.1)
				(type default)
			)
			(layer "B.Fab")
		)
		(pad "1" smd circle
			(at 0.40005 0 270)
			(size 0 0)
			(layers "B.Cu" "B.Mask" "B.Paste")
			(net "BRICK_P12V0_EN_N")
		)
		(pad "2" smd circle
			(at -0.40005 0 270)
			(size 0 0)
			(layers "B.Cu" "B.Mask" "B.Paste")
			(net "GND")
		)
	)
	(footprint ""
		(layer "B.Cu")
		(at 216.408 -84.455 90)
		(property "Reference" "R5903"
			(at 0 0 90)
			(layer "B.SilkS")
			(hide yes)
			(effects
				(font
					(size 1.27 1.27)
				)
				(justify mirror)
			)
		)
		(property "Value" ""
			(at 0 0 90)
			(layer "B.Fab")
			(effects
				(font
					(size 1.27 1.27)
				)
				(justify mirror)
			)
		)
		(duplicate_pad_numbers_are_jumpers no)
		(fp_line
			(start 0.7874 -0.4064)
			(end -0.7874 -0.4064)
			(stroke
				(width 0.1524)
				(type default)
			)
			(layer "B.SilkS")
		)
		(fp_line
			(start -0.7874 -0.4064)
			(end -0.7874 0.4064)
			(stroke
				(width 0.1524)
				(type default)
			)
			(layer "B.SilkS")
		)
		(fp_line
			(start 0.7874 0.4064)
			(end 0.7874 -0.4064)
			(stroke
				(width 0.1524)
				(type default)
			)
			(layer "B.SilkS")
		)
		(fp_line
			(start -0.7874 0.4064)
			(end 0.7874 0.4064)
			(stroke
				(width 0.1524)
				(type default)
			)
			(layer "B.SilkS")
		)
		(fp_line
			(start 0.67945 -0.305054)
			(end 0.12065 -0.305054)
			(stroke
				(width 0.1)
				(type default)
			)
			(layer "B.Fab")
		)
		(fp_line
			(start 0.12065 -0.305054)
			(end 0.12065 -0.2794)
			(stroke
				(width 0.1)
				(type default)
			)
			(layer "B.Fab")
		)
		(fp_line
			(start -0.12065 -0.3048)
			(end -0.67945 -0.3048)
			(stroke
				(width 0.1)
				(type default)
			)
			(layer "B.Fab")
		)
		(fp_line
			(start -0.67945 -0.3048)
			(end -0.67945 0.3048)
			(stroke
				(width 0.1)
				(type default)
			)
			(layer "B.Fab")
		)
		(fp_line
			(start 0.12065 -0.2794)
			(end -0.12065 -0.2794)
			(stroke
				(width 0.1)
				(type default)
			)
			(layer "B.Fab")
		)
		(fp_line
			(start -0.12065 -0.2794)
			(end -0.12065 -0.3048)
			(stroke
				(width 0.1)
				(type default)
			)
			(layer "B.Fab")
		)
		(fp_line
			(start 0.12065 0.2794)
			(end 0.12065 0.3048)
			(stroke
				(width 0.1)
				(type default)
			)
			(layer "B.Fab")
		)
		(fp_line
			(start -0.120396 0.2794)
			(end 0.12065 0.2794)
			(stroke
				(width 0.1)
				(type default)
			)
			(layer "B.Fab")
		)
		(fp_line
			(start 0.67945 0.3048)
			(end 0.67945 -0.305054)
			(stroke
				(width 0.1)
				(type default)
			)
			(layer "B.Fab")
		)
		(fp_line
			(start 0.12065 0.3048)
			(end 0.67945 0.3048)
			(stroke
				(width 0.1)
				(type default)
			)
			(layer "B.Fab")
		)
		(fp_line
			(start -0.120396 0.3048)
			(end -0.120396 0.2794)
			(stroke
				(width 0.1)
				(type default)
			)
			(layer "B.Fab")
		)
		(fp_line
			(start -0.67945 0.3048)
			(end -0.120396 0.3048)
			(stroke
				(width 0.1)
				(type default)
			)
			(layer "B.Fab")
		)
		(pad "1" smd circle
			(at 0.40005 0 270)
			(size 0 0)
			(layers "B.Cu" "B.Mask" "B.Paste")
			(net "FAN_PWR_EN")
		)
		(pad "2" smd circle
			(at -0.40005 0 270)
			(size 0 0)
			(layers "B.Cu" "B.Mask" "B.Paste")
			(net "P3V3_AUX")
		)
	)
	(footprint ""
		(layer "B.Cu")
		(at 179.065174 -76.327 180)
		(property "Reference" "R198"
			(at 0 0 0)
			(layer "B.SilkS")
			(hide yes)
			(effects
				(font
					(size 1.27 1.27)
				)
				(justify mirror)
			)
		)
		(property "Value" ""
			(at 0 0 0)
			(layer "B.Fab")
			(effects
				(font
					(size 1.27 1.27)
				)
				(justify mirror)
			)
		)
		(duplicate_pad_numbers_are_jumpers no)
		(fp_line
			(start 0.7874 0.4064)
			(end 0.7874 -0.4064)
			(stroke
				(width 0.1524)
				(type default)
			)
			(layer "B.SilkS")
		)
		(fp_line
			(start 0.7874 -0.4064)
			(end -0.7874 -0.4064)
			(stroke
				(width 0.1524)
				(type default)
			)
			(layer "B.SilkS")
		)
		(fp_line
			(start -0.7874 0.4064)
			(end 0.7874 0.4064)
			(stroke
				(width 0.1524)
				(type default)
			)
			(layer "B.SilkS")
		)
		(fp_line
			(start -0.7874 -0.4064)
			(end -0.7874 0.4064)
			(stroke
				(width 0.1524)
				(type default)
			)
			(layer "B.SilkS")
		)
		(fp_line
			(start 0.67945 0.3048)
			(end 0.67945 -0.305054)
			(stroke
				(width 0.1)
				(type default)
			)
			(layer "B.Fab")
		)
		(fp_line
			(start 0.67945 -0.305054)
			(end 0.12065 -0.305054)
			(stroke
				(width 0.1)
				(type default)
			)
			(layer "B.Fab")
		)
		(fp_line
			(start 0.12065 0.3048)
			(end 0.67945 0.3048)
			(stroke
				(width 0.1)
				(type default)
			)
			(layer "B.Fab")
		)
		(fp_line
			(start 0.12065 0.2794)
			(end 0.12065 0.3048)
			(stroke
				(width 0.1)
				(type default)
			)
			(layer "B.Fab")
		)
		(fp_line
			(start 0.12065 -0.2794)
			(end -0.12065 -0.2794)
			(stroke
				(width 0.1)
				(type default)
			)
			(layer "B.Fab")
		)
		(fp_line
			(start 0.12065 -0.305054)
			(end 0.12065 -0.2794)
			(stroke
				(width 0.1)
				(type default)
			)
			(layer "B.Fab")
		)
		(fp_line
			(start -0.120396 0.3048)
			(end -0.120396 0.2794)
			(stroke
				(width 0.1)
				(type default)
			)
			(layer "B.Fab")
		)
		(fp_line
			(start -0.120396 0.2794)
			(end 0.12065 0.2794)
			(stroke
				(width 0.1)
				(type default)
			)
			(layer "B.Fab")
		)
		(fp_line
			(start -0.12065 -0.2794)
			(end -0.12065 -0.3048)
			(stroke
				(width 0.1)
				(type default)
			)
			(layer "B.Fab")
		)
		(fp_line
			(start -0.12065 -0.3048)
			(end -0.67945 -0.3048)
			(stroke
				(width 0.1)
				(type default)
			)
			(layer "B.Fab")
		)
		(fp_line
			(start -0.67945 0.3048)
			(end -0.120396 0.3048)
			(stroke
				(width 0.1)
				(type default)
			)
			(layer "B.Fab")
		)
		(fp_line
			(start -0.67945 -0.3048)
			(end -0.67945 0.3048)
			(stroke
				(width 0.1)
				(type default)
			)
			(layer "B.Fab")
		)
		(pad "1" smd circle
			(at 0.40005 0)
			(size 0 0)
			(layers "B.Cu" "B.Mask" "B.Paste")
			(net "SMB_P52V_VPDB_SCL")
		)
		(pad "2" smd circle
			(at -0.40005 0)
			(size 0 0)
			(layers "B.Cu" "B.Mask" "B.Paste")
			(net "SMB_BRICK2_SCL")
		)
	)
	(footprint ""
		(layer "B.Cu")
		(at 217.424 -69.723 -90)
		(property "Reference" "R135"
			(at 0 0 90)
			(layer "B.SilkS")
			(hide yes)
			(effects
				(font
					(size 1.27 1.27)
				)
				(justify mirror)
			)
		)
		(property "Value" ""
			(at 0 0 90)
			(layer "B.Fab")
			(effects
				(font
					(size 1.27 1.27)
				)
				(justify mirror)
			)
		)
		(duplicate_pad_numbers_are_jumpers no)
		(fp_line
			(start -0.7874 0.4064)
			(end 0.7874 0.4064)
			(stroke
				(width 0.1524)
				(type default)
			)
			(layer "B.SilkS")
		)
		(fp_line
			(start 0.7874 0.4064)
			(end 0.7874 -0.4064)
			(stroke
				(width 0.1524)
				(type default)
			)
			(layer "B.SilkS")
		)
		(fp_line
			(start -0.7874 -0.4064)
			(end -0.7874 0.4064)
			(stroke
				(width 0.1524)
				(type default)
			)
			(layer "B.SilkS")
		)
		(fp_line
			(start 0.7874 -0.4064)
			(end -0.7874 -0.4064)
			(stroke
				(width 0.1524)
				(type default)
			)
			(layer "B.SilkS")
		)
		(fp_line
			(start -0.67945 0.3048)
			(end -0.120396 0.3048)
			(stroke
				(width 0.1)
				(type default)
			)
			(layer "B.Fab")
		)
		(fp_line
			(start -0.120396 0.3048)
			(end -0.120396 0.2794)
			(stroke
				(width 0.1)
				(type default)
			)
			(layer "B.Fab")
		)
		(fp_line
			(start 0.12065 0.3048)
			(end 0.67945 0.3048)
			(stroke
				(width 0.1)
				(type default)
			)
			(layer "B.Fab")
		)
		(fp_line
			(start 0.67945 0.3048)
			(end 0.67945 -0.305054)
			(stroke
				(width 0.1)
				(type default)
			)
			(layer "B.Fab")
		)
		(fp_line
			(start -0.120396 0.2794)
			(end 0.12065 0.2794)
			(stroke
				(width 0.1)
				(type default)
			)
			(layer "B.Fab")
		)
		(fp_line
			(start 0.12065 0.2794)
			(end 0.12065 0.3048)
			(stroke
				(width 0.1)
				(type default)
			)
			(layer "B.Fab")
		)
		(fp_line
			(start -0.12065 -0.2794)
			(end -0.12065 -0.3048)
			(stroke
				(width 0.1)
				(type default)
			)
			(layer "B.Fab")
		)
		(fp_line
			(start 0.12065 -0.2794)
			(end -0.12065 -0.2794)
			(stroke
				(width 0.1)
				(type default)
			)
			(layer "B.Fab")
		)
		(fp_line
			(start -0.67945 -0.3048)
			(end -0.67945 0.3048)
			(stroke
				(width 0.1)
				(type default)
			)
			(layer "B.Fab")
		)
		(fp_line
			(start -0.12065 -0.3048)
			(end -0.67945 -0.3048)
			(stroke
				(width 0.1)
				(type default)
			)
			(layer "B.Fab")
		)
		(fp_line
			(start 0.12065 -0.305054)
			(end 0.12065 -0.2794)
			(stroke
				(width 0.1)
				(type default)
			)
			(layer "B.Fab")
		)
		(fp_line
			(start 0.67945 -0.305054)
			(end 0.12065 -0.305054)
			(stroke
				(width 0.1)
				(type default)
			)
			(layer "B.Fab")
		)
		(pad "1" smd circle
			(at 0.40005 0 90)
			(size 0 0)
			(layers "B.Cu" "B.Mask" "B.Paste")
			(net "P3V3_AUX")
		)
		(pad "2" smd circle
			(at -0.40005 0 90)
			(size 0 0)
			(layers "B.Cu" "B.Mask" "B.Paste")
			(net "BOARD_ID_0")
		)
	)
)
